(kicad_pcb
	(version 20260206)
	(generator "pcbnew")
	(generator_version "10.0")
	(general
		(thickness 1.6)
		(legacy_teardrops no)
	)
	(paper "A4")
	(title_block
		(title "04192023_DAF0TMB3IC0_F0TG_MB_C_brd_V02_OCP.brd")
		(comment 1 "Grand Teton / footprints 222-225 of 8354")
	)
	(layers
		(0 "F.Cu" signal "TOP")
		(4 "In1.Cu" signal "GND")
		(6 "In2.Cu" signal "IN1")
		(8 "In3.Cu" signal "GND1")
		(10 "In4.Cu" signal "IN2")
		(12 "In5.Cu" signal "GND2")
		(14 "In6.Cu" signal "IN3")
		(16 "In7.Cu" signal "GND3")
		(18 "In8.Cu" signal "VCC")
		(20 "In9.Cu" signal "VCC1")
		(22 "In10.Cu" signal "GND4")
		(24 "In11.Cu" signal "IN4")
		(26 "In12.Cu" signal "GND5")
		(28 "In13.Cu" signal "IN5")
		(30 "In14.Cu" signal "GND6")
		(32 "In15.Cu" signal "IN6")
		(34 "In16.Cu" signal "GND7")
		(2 "B.Cu" signal "BOTTOM")
		(9 "F.Adhes" user "F.Adhesive")
		(11 "B.Adhes" user "B.Adhesive")
		(13 "F.Paste" user "Package Geometry/Pastemask Top")
		(15 "B.Paste" user "Package Geometry/Pastemask Bottom")
		(5 "F.SilkS" user "Ref Des/Silkscreen Top")
		(7 "B.SilkS" user "Ref Des/Silkscreen Bottom")
		(1 "F.Mask" user "Board Geometry/Soldermask Top")
		(3 "B.Mask" user "Board Geometry/Soldermask Bottom")
		(17 "Dwgs.User" user "User.Drawings")
		(19 "Cmts.User" user "User.Comments")
		(21 "Eco1.User" user "User.Eco1")
		(23 "Eco2.User" user "User.Eco2")
		(25 "Edge.Cuts" user "Board Geometry/Outline")
		(27 "Margin" user)
		(31 "F.CrtYd" user "Package Geometry/Place Bound Top")
		(29 "B.CrtYd" user "Package Geometry/Place Bound Bottom")
		(35 "F.Fab" user "Ref Des/Assembly Top")
		(33 "B.Fab" user "Ref Des/Assembly Bottom")
	)
	(footprint ""
		(layer "F.Cu")
		(at 34.252662 -424.710098 180)
		(property "Reference" "U237"
			(at -6.560312 3.07086 0)
			(unlocked yes)
			(layer "F.SilkS")
			(effects
				(font
					(size 0.7874 0.5842)
					(thickness 0.1524)
				)
				(justify left)
			)
		)
		(property "Value" ""
			(at 0 0 180)
			(layer "F.Fab")
			(effects
				(font
					(size 1.27 1.27)
				)
			)
		)
		(duplicate_pad_numbers_are_jumpers no)
		(fp_line
			(start 2.5146 0.2032)
			(end 1.7018 0.2032)
			(stroke
				(width 0.1524)
				(type default)
			)
			(layer "F.SilkS")
		)
		(fp_line
			(start 1.6891 -1.8034)
			(end 2.0701 -1.8034)
			(stroke
				(width 0.1524)
				(type default)
			)
			(layer "F.SilkS")
		)
		(fp_line
			(start 1.299972 2.29997)
			(end 1.299972 2.015998)
			(stroke
				(width 0.1524)
				(type default)
			)
			(layer "F.SilkS")
		)
		(fp_line
			(start 1.299972 -2.015998)
			(end 1.299972 -2.29997)
			(stroke
				(width 0.1524)
				(type default)
			)
			(layer "F.SilkS")
		)
		(fp_line
			(start 1.299972 -2.29997)
			(end 1.016 -2.29997)
			(stroke
				(width 0.1524)
				(type default)
			)
			(layer "F.SilkS")
		)
		(fp_line
			(start 1.016 2.29997)
			(end 1.299972 2.29997)
			(stroke
				(width 0.1524)
				(type default)
			)
			(layer "F.SilkS")
		)
		(fp_line
			(start 0.7874 3.0861)
			(end 0.7874 2.7051)
			(stroke
				(width 0.1524)
				(type default)
			)
			(layer "F.SilkS")
		)
		(fp_line
			(start -0.8128 -2.6924)
			(end -0.8128 -3.5052)
			(stroke
				(width 0.1524)
				(type default)
			)
			(layer "F.SilkS")
		)
		(fp_line
			(start -1.016 -2.29997)
			(end -1.299972 -2.29997)
			(stroke
				(width 0.1524)
				(type default)
			)
			(layer "F.SilkS")
		)
		(fp_line
			(start -1.299972 2.29997)
			(end -1.016 2.29997)
			(stroke
				(width 0.1524)
				(type default)
			)
			(layer "F.SilkS")
		)
		(fp_line
			(start -1.299972 2.015998)
			(end -1.299972 2.29997)
			(stroke
				(width 0.1524)
				(type default)
			)
			(layer "F.SilkS")
		)
		(fp_line
			(start -1.299972 -2.29997)
			(end -1.299972 -2.015998)
			(stroke
				(width 0.1524)
				(type default)
			)
			(layer "F.SilkS")
		)
		(fp_line
			(start -1.6891 -0.2032)
			(end -1.974596 -0.2032)
			(stroke
				(width 0.1524)
				(type default)
			)
			(layer "F.SilkS")
		)
		(fp_line
			(start -1.7018 1.8034)
			(end -2.5146 1.8034)
			(stroke
				(width 0.1524)
				(type default)
			)
			(layer "F.SilkS")
		)
		(fp_poly
			(pts
				(xy -2.238248 -2.068322) (xy -1.7018 -1.800098) (xy -2.238248 -1.531874)
			)
			(stroke
				(width 0)
				(type default)
			)
			(fill yes)
			(layer "F.SilkS")
		)
		(fp_line
			(start 2.5146 0.2032)
			(end 1.7018 0.2032)
			(stroke
				(width 0.1)
				(type default)
			)
			(layer "F.Fab")
		)
		(fp_line
			(start 1.6891 -1.8034)
			(end 2.0701 -1.8034)
			(stroke
				(width 0.1)
				(type default)
			)
			(layer "F.Fab")
		)
		(fp_line
			(start 1.299972 2.29997)
			(end 1.299972 -2.29997)
			(stroke
				(width 0.1)
				(type default)
			)
			(layer "F.Fab")
		)
		(fp_line
			(start 1.299972 -2.29997)
			(end -1.299972 -2.29997)
			(stroke
				(width 0.1)
				(type default)
			)
			(layer "F.Fab")
		)
		(fp_line
			(start 0.7874 3.0861)
			(end 0.7874 2.7051)
			(stroke
				(width 0.1)
				(type default)
			)
			(layer "F.Fab")
		)
		(fp_line
			(start -0.8128 -2.6924)
			(end -0.8128 -3.5052)
			(stroke
				(width 0.1)
				(type default)
			)
			(layer "F.Fab")
		)
		(fp_line
			(start -1.299972 2.29997)
			(end 1.299972 2.29997)
			(stroke
				(width 0.1)
				(type default)
			)
			(layer "F.Fab")
		)
		(fp_line
			(start -1.299972 -2.29997)
			(end -1.299972 2.29997)
			(stroke
				(width 0.1)
				(type default)
			)
			(layer "F.Fab")
		)
		(fp_line
			(start -1.6891 -0.2032)
			(end -2.0701 -0.2032)
			(stroke
				(width 0.1)
				(type default)
			)
			(layer "F.Fab")
		)
		(fp_line
			(start -1.7018 1.8034)
			(end -2.5146 1.8034)
			(stroke
				(width 0.1)
				(type default)
			)
			(layer "F.Fab")
		)
		(fp_poly
			(pts
				(xy -2.7178 -2.308098) (xy -2.7178 -1.292098) (xy -1.7018 -1.800098)
			)
			(stroke
				(width 0)
				(type default)
			)
			(fill yes)
			(layer "F.Fab")
		)
		(fp_text user "25"
			(at 4.134358 -1.752854 90)
			(unlocked yes)
			(layer "F.SilkS")
			(effects
				(font
					(size 0.635 0.4064)
					(thickness 0.1524)
				)
			)
		)
		(fp_text user "16"
			(at 2.821432 2.50317 90)
			(unlocked yes)
			(layer "F.SilkS")
			(effects
				(font
					(size 0.635 0.4064)
					(thickness 0.1524)
				)
			)
		)
		(fp_text user "26"
			(at 2.66446 -4.066794 90)
			(unlocked yes)
			(layer "F.SilkS")
			(effects
				(font
					(size 0.635 0.4064)
					(thickness 0.1524)
				)
			)
		)
		(fp_text user "15"
			(at 1.616456 3.538728 90)
			(unlocked yes)
			(layer "F.SilkS")
			(effects
				(font
					(size 0.635 0.4064)
					(thickness 0.1524)
				)
			)
		)
		(fp_text user "11"
			(at -1.56337 3.733292 90)
			(unlocked yes)
			(layer "F.SilkS")
			(effects
				(font
					(size 0.635 0.4064)
					(thickness 0.1524)
				)
			)
		)
		(fp_text user "30"
			(at -2.718816 -2.527808 90)
			(unlocked yes)
			(layer "F.SilkS")
			(effects
				(font
					(size 0.635 0.4064)
					(thickness 0.1524)
				)
			)
		)
		(fp_text user "10"
			(at -4.529582 2.764028 90)
			(unlocked yes)
			(layer "F.SilkS")
			(effects
				(font
					(size 0.635 0.4064)
					(thickness 0.1524)
				)
			)
		)
		(fp_text user "16"
			(at 2.029968 2.0574 90)
			(unlocked yes)
			(layer "F.Fab")
			(effects
				(font
					(size 0.635 0.4064)
					(thickness 0.1524)
				)
			)
		)
		(fp_text user "25"
			(at 1.979168 -2.4384 90)
			(unlocked yes)
			(layer "F.Fab")
			(effects
				(font
					(size 0.635 0.4064)
					(thickness 0.1524)
				)
			)
		)
		(fp_text user "15"
			(at 1.3716 2.948432 180)
			(unlocked yes)
			(layer "F.Fab")
			(effects
				(font
					(size 0.635 0.4064)
					(thickness 0.1524)
				)
			)
		)
		(fp_text user "26"
			(at 1.0922 -3.071368 180)
			(unlocked yes)
			(layer "F.Fab")
			(effects
				(font
					(size 0.635 0.4064)
					(thickness 0.1524)
				)
			)
		)
		(fp_text user "11"
			(at -1.2192 3.075432 180)
			(unlocked yes)
			(layer "F.Fab")
			(effects
				(font
					(size 0.635 0.4064)
					(thickness 0.1524)
				)
			)
		)
		(fp_text user "30"
			(at -1.4478 -2.842768 180)
			(unlocked yes)
			(layer "F.Fab")
			(effects
				(font
					(size 0.635 0.4064)
					(thickness 0.1524)
				)
			)
		)
		(fp_text user "10"
			(at -2.084832 2.3876 90)
			(unlocked yes)
			(layer "F.Fab")
			(effects
				(font
					(size 0.635 0.4064)
					(thickness 0.1524)
				)
			)
		)
		(pad "1" smd circle
			(at -1.249934 -1.800098 90)
			(size 0 0)
			(layers "F.Cu" "F.Mask" "F.Paste")
			(net "P3V3_AUX")
		)
		(pad "2" smd circle
			(at -1.249934 -1.400048 90)
			(size 0 0)
			(layers "F.Cu" "F.Mask" "F.Paste")
			(net "P2E_MB_BMC_TX_C_R1_DP<0>")
		)
		(pad "3" smd circle
			(at -1.249934 -0.999998 90)
			(size 0 0)
			(layers "F.Cu" "F.Mask" "F.Paste")
			(net "P2E_MB_BMC_TX_C_R1_DN<0>")
		)
		(pad "4" smd circle
			(at -1.249934 -0.599948 90)
			(size 0 0)
			(layers "F.Cu" "F.Mask" "F.Paste")
			(net "GND")
		)
		(pad "5" smd circle
			(at -1.249934 -0.199898 90)
			(size 0 0)
			(layers "F.Cu" "F.Mask" "F.Paste")
			(net "PU_TEST")
		)
		(pad "6" smd circle
			(at -1.249934 0.199898 90)
			(size 0 0)
			(layers "F.Cu" "F.Mask" "F.Paste")
			(net "GND")
		)
		(pad "7" smd circle
			(at -1.249934 0.599948 90)
			(size 0 0)
			(layers "F.Cu" "F.Mask" "F.Paste")
			(net "GND")
		)
		(pad "8" smd circle
			(at -1.249934 0.999998 90)
			(size 0 0)
			(layers "F.Cu" "F.Mask" "F.Paste")
			(net "P2E_MB_BMC_RX_BUF_C_DN<0>")
		)
		(pad "9" smd circle
			(at -1.249934 1.400048 90)
			(size 0 0)
			(layers "F.Cu" "F.Mask" "F.Paste")
			(net "P2E_MB_BMC_RX_BUF_C_DP<0>")
		)
		(pad "10" smd circle
			(at -1.249934 1.800098 90)
			(size 0 0)
			(layers "F.Cu" "F.Mask" "F.Paste")
			(net "P3V3_AUX")
		)
		(pad "11" smd circle
			(at -0.8001 2.249932 180)
			(size 0 0)
			(layers "F.Cu" "F.Mask" "F.Paste")
			(net "FM_P2E_EN_N")
		)
		(pad "12" smd circle
			(at -0.40005 2.249932 180)
			(size 0 0)
			(layers "F.Cu" "F.Mask" "F.Paste")
			(net "FM_P2E_SWB")
		)
		(pad "13" smd circle
			(at 0 2.249932 180)
			(size 0 0)
			(layers "F.Cu" "F.Mask" "F.Paste")
			(net "GND")
		)
		(pad "14" smd circle
			(at 0.40005 2.249932 180)
			(size 0 0)
			(layers "F.Cu" "F.Mask" "F.Paste")
			(net "FM_P2E_FGB")
		)
		(pad "15" smd circle
			(at 0.8001 2.249932 180)
			(size 0 0)
			(layers "F.Cu" "F.Mask" "F.Paste")
			(net "FM_P2E_EQB1")
		)
		(pad "16" smd circle
			(at 1.249934 1.800098 270)
			(size 0 0)
			(layers "F.Cu" "F.Mask" "F.Paste")
			(net "P3V3_AUX")
		)
		(pad "17" smd circle
			(at 1.249934 1.400048 270)
			(size 0 0)
			(layers "F.Cu" "F.Mask" "F.Paste")
			(net "P2E_MB_BMC_RX_R1_DP<0>")
		)
		(pad "18" smd circle
			(at 1.249934 0.999998 270)
			(size 0 0)
			(layers "F.Cu" "F.Mask" "F.Paste")
			(net "P2E_MB_BMC_RX_R1_DN<0>")
		)
		(pad "19" smd circle
			(at 1.249934 0.599948 270)
			(size 0 0)
			(layers "F.Cu" "F.Mask" "F.Paste")
			(net "GND")
		)
		(pad "20" smd circle
			(at 1.249934 0.199898 270)
			(size 0 0)
			(layers "F.Cu" "F.Mask" "F.Paste")
			(net "FM_P2E_EQB0")
		)
		(pad "21" smd circle
			(at 1.249934 -0.199898 270)
			(size 0 0)
			(layers "F.Cu" "F.Mask" "F.Paste")
			(net "FM_P2E_EQA0")
		)
		(pad "22" smd circle
			(at 1.249934 -0.599948 270)
			(size 0 0)
			(layers "F.Cu" "F.Mask" "F.Paste")
			(net "GND")
		)
		(pad "23" smd circle
			(at 1.249934 -0.999998 270)
			(size 0 0)
			(layers "F.Cu" "F.Mask" "F.Paste")
			(net "P2E_MB_BMC_TX_BUF_DN<0>")
		)
		(pad "24" smd circle
			(at 1.249934 -1.400048 270)
			(size 0 0)
			(layers "F.Cu" "F.Mask" "F.Paste")
			(net "P2E_MB_BMC_TX_BUF_DP<0>")
		)
		(pad "25" smd circle
			(at 1.249934 -1.800098 270)
			(size 0 0)
			(layers "F.Cu" "F.Mask" "F.Paste")
			(net "P3V3_AUX")
		)
		(pad "26" smd circle
			(at 0.8001 -2.249932)
			(size 0 0)
			(layers "F.Cu" "F.Mask" "F.Paste")
			(net "FM_P2E_EQA1")
		)
		(pad "27" smd circle
			(at 0.40005 -2.249932)
			(size 0 0)
			(layers "F.Cu" "F.Mask" "F.Paste")
			(net "FM_P2E_FGA")
		)
		(pad "28" smd circle
			(at 0 -2.249932)
			(size 0 0)
			(layers "F.Cu" "F.Mask" "F.Paste")
			(net "GND")
		)
		(pad "29" smd circle
			(at -0.40005 -2.249932)
			(size 0 0)
			(layers "F.Cu" "F.Mask" "F.Paste")
			(net "FM_P2E_SWA")
		)
		(pad "30" smd circle
			(at -0.8001 -2.249932)
			(size 0 0)
			(layers "F.Cu" "F.Mask" "F.Paste")
			(net "FM_P2E_MODE")
		)
		(pad "TH" smd rect
			(at 0 0 180)
			(size 1.2192 3.2004)
			(layers "F.Cu" "F.Mask" "F.Paste")
			(net "GND")
		)
	)
	(footprint ""
		(layer "F.Cu")
		(at 130.49758 -27.52598 90)
		(property "Reference" "R6190"
			(at 0 0 90)
			(layer "F.SilkS")
			(hide yes)
			(effects
				(font
					(size 1.27 1.27)
				)
			)
		)
		(property "Value" ""
			(at 0 0 90)
			(layer "F.Fab")
			(effects
				(font
					(size 1.27 1.27)
				)
			)
		)
		(duplicate_pad_numbers_are_jumpers no)
		(fp_line
			(start 0.32512 -0.175006)
			(end 0.32512 0.175006)
			(stroke
				(width 0.1)
				(type default)
			)
			(layer "F.Fab")
		)
		(fp_line
			(start -0.32512 -0.175006)
			(end 0.32512 -0.175006)
			(stroke
				(width 0.1)
				(type default)
			)
			(layer "F.Fab")
		)
		(fp_line
			(start 0.32512 0.175006)
			(end -0.32512 0.175006)
			(stroke
				(width 0.1)
				(type default)
			)
			(layer "F.Fab")
		)
		(fp_line
			(start -0.32512 0.175006)
			(end -0.32512 -0.175006)
			(stroke
				(width 0.1)
				(type default)
			)
			(layer "F.Fab")
		)
		(pad "1" smd rect
			(at -0.2667 0 90)
			(size 0.3048 0.381)
			(layers "F.Cu" "F.Mask" "F.Paste")
			(net "USB2_CPU0_P0_DP")
		)
		(pad "2" smd rect
			(at 0.2667 0 270)
			(size 0.3048 0.381)
			(layers "F.Cu" "F.Mask" "F.Paste")
			(net "USB2_CPU0_P0_R1_DP")
		)
	)
	(footprint ""
		(layer "F.Cu")
		(at 170.970702 -437.032146 90)
		(property "Reference" "R3433"
			(at 0 0 90)
			(layer "F.SilkS")
			(hide yes)
			(effects
				(font
					(size 1.27 1.27)
				)
			)
		)
		(property "Value" ""
			(at 0 0 90)
			(layer "F.Fab")
			(effects
				(font
					(size 1.27 1.27)
				)
			)
		)
		(duplicate_pad_numbers_are_jumpers no)
		(fp_line
			(start 0.7874 -0.4064)
			(end 0.7874 0.4064)
			(stroke
				(width 0.1524)
				(type default)
			)
			(layer "F.SilkS")
		)
		(fp_line
			(start -0.7874 -0.4064)
			(end 0.7874 -0.4064)
			(stroke
				(width 0.1524)
				(type default)
			)
			(layer "F.SilkS")
		)
		(fp_line
			(start 0.7874 0.4064)
			(end -0.7874 0.4064)
			(stroke
				(width 0.1524)
				(type default)
			)
			(layer "F.SilkS")
		)
		(fp_line
			(start -0.7874 0.4064)
			(end -0.7874 -0.4064)
			(stroke
				(width 0.1524)
				(type default)
			)
			(layer "F.SilkS")
		)
		(fp_line
			(start -0.12065 -0.305054)
			(end -0.12065 -0.2794)
			(stroke
				(width 0.1)
				(type default)
			)
			(layer "F.Fab")
		)
		(fp_line
			(start -0.67945 -0.305054)
			(end -0.12065 -0.305054)
			(stroke
				(width 0.1)
				(type default)
			)
			(layer "F.Fab")
		)
		(fp_line
			(start 0.67945 -0.3048)
			(end 0.67945 0.3048)
			(stroke
				(width 0.1)
				(type default)
			)
			(layer "F.Fab")
		)
		(fp_line
			(start 0.12065 -0.3048)
			(end 0.67945 -0.3048)
			(stroke
				(width 0.1)
				(type default)
			)
			(layer "F.Fab")
		)
		(fp_line
			(start 0.12065 -0.2794)
			(end 0.12065 -0.3048)
			(stroke
				(width 0.1)
				(type default)
			)
			(layer "F.Fab")
		)
		(fp_line
			(start -0.12065 -0.2794)
			(end 0.12065 -0.2794)
			(stroke
				(width 0.1)
				(type default)
			)
			(layer "F.Fab")
		)
		(fp_line
			(start 0.120396 0.2794)
			(end -0.12065 0.2794)
			(stroke
				(width 0.1)
				(type default)
			)
			(layer "F.Fab")
		)
		(fp_line
			(start -0.12065 0.2794)
			(end -0.12065 0.3048)
			(stroke
				(width 0.1)
				(type default)
			)
			(layer "F.Fab")
		)
		(fp_line
			(start 0.67945 0.3048)
			(end 0.120396 0.3048)
			(stroke
				(width 0.1)
				(type default)
			)
			(layer "F.Fab")
		)
		(fp_line
			(start 0.120396 0.3048)
			(end 0.120396 0.2794)
			(stroke
				(width 0.1)
				(type default)
			)
			(layer "F.Fab")
		)
		(fp_line
			(start -0.12065 0.3048)
			(end -0.67945 0.3048)
			(stroke
				(width 0.1)
				(type default)
			)
			(layer "F.Fab")
		)
		(fp_line
			(start -0.67945 0.3048)
			(end -0.67945 -0.305054)
			(stroke
				(width 0.1)
				(type default)
			)
			(layer "F.Fab")
		)
		(pad "1" smd circle
			(at -0.40005 0 90)
			(size 0 0)
			(layers "F.Cu" "F.Mask" "F.Paste")
			(net "P3V3_AUX")
		)
		(pad "2" smd circle
			(at 0.40005 0 90)
			(size 0 0)
			(layers "F.Cu" "F.Mask" "F.Paste")
			(net "GPU_BASE_HMC_READY_N")
		)
	)
	(footprint ""
		(layer "F.Cu")
		(at 328.506836 -150.589234 180)
		(property "Reference" "PR418"
			(at 0 0 180)
			(layer "F.SilkS")
			(hide yes)
			(effects
				(font
					(size 1.27 1.27)
				)
			)
		)
		(property "Value" ""
			(at 0 0 180)
			(layer "F.Fab")
			(effects
				(font
					(size 1.27 1.27)
				)
			)
		)
		(duplicate_pad_numbers_are_jumpers no)
		(fp_line
			(start 0.7874 0.4064)
			(end -0.7874 0.4064)
			(stroke
				(width 0.1524)
				(type default)
			)
			(layer "F.SilkS")
		)
		(fp_line
			(start 0.7874 -0.4064)
			(end 0.7874 0.4064)
			(stroke
				(width 0.1524)
				(type default)
			)
			(layer "F.SilkS")
		)
		(fp_line
			(start -0.7874 0.4064)
			(end -0.7874 -0.4064)
			(stroke
				(width 0.1524)
				(type default)
			)
			(layer "F.SilkS")
		)
		(fp_line
			(start -0.7874 -0.4064)
			(end 0.7874 -0.4064)
			(stroke
				(width 0.1524)
				(type default)
			)
			(layer "F.SilkS")
		)
		(fp_line
			(start 0.67945 0.3048)
			(end 0.120396 0.3048)
			(stroke
				(width 0.1)
				(type default)
			)
			(layer "F.Fab")
		)
		(fp_line
			(start 0.67945 -0.3048)
			(end 0.67945 0.3048)
			(stroke
				(width 0.1)
				(type default)
			)
			(layer "F.Fab")
		)
		(fp_line
			(start 0.12065 -0.2794)
			(end 0.12065 -0.3048)
			(stroke
				(width 0.1)
				(type default)
			)
			(layer "F.Fab")
		)
		(fp_line
			(start 0.12065 -0.3048)
			(end 0.67945 -0.3048)
			(stroke
				(width 0.1)
				(type default)
			)
			(layer "F.Fab")
		)
		(fp_line
			(start 0.120396 0.3048)
			(end 0.120396 0.2794)
			(stroke
				(width 0.1)
				(type default)
			)
			(layer "F.Fab")
		)
		(fp_line
			(start 0.120396 0.2794)
			(end -0.12065 0.2794)
			(stroke
				(width 0.1)
				(type default)
			)
			(layer "F.Fab")
		)
		(fp_line
			(start -0.12065 0.3048)
			(end -0.67945 0.3048)
			(stroke
				(width 0.1)
				(type default)
			)
			(layer "F.Fab")
		)
		(fp_line
			(start -0.12065 0.2794)
			(end -0.12065 0.3048)
			(stroke
				(width 0.1)
				(type default)
			)
			(layer "F.Fab")
		)
		(fp_line
			(start -0.12065 -0.2794)
			(end 0.12065 -0.2794)
			(stroke
				(width 0.1)
				(type default)
			)
			(layer "F.Fab")
		)
		(fp_line
			(start -0.12065 -0.305054)
			(end -0.12065 -0.2794)
			(stroke
				(width 0.1)
				(type default)
			)
			(layer "F.Fab")
		)
		(fp_line
			(start -0.67945 0.3048)
			(end -0.67945 -0.305054)
			(stroke
				(width 0.1)
				(type default)
			)
			(layer "F.Fab")
		)
		(fp_line
			(start -0.67945 -0.305054)
			(end -0.12065 -0.305054)
			(stroke
				(width 0.1)
				(type default)
			)
			(layer "F.Fab")
		)
		(pad "1" smd circle
			(at -0.40005 0 180)
			(size 0 0)
			(layers "F.Cu" "F.Mask" "F.Paste")
			(net "GND")
		)
		(pad "2" smd circle
			(at 0.40005 0 180)
			(size 0 0)
			(layers "F.Cu" "F.Mask" "F.Paste")
			(net "PVDD18_S5_P0_RGND")
		)
	)
)
